G04 ================== begin FILE IDENTIFICATION RECORD ==================*
G04 Layout Name:  14545-sa.brd*
G04 Film Name:    BSILK*
G04 File Format:  Gerber RS274X*
G04 File Origin:  Cadence Allegro 16.5-S056*
G04 Origin Date:  Fri Aug 01 17:58:10 2014*
G04 *
G04 Layer:  VIA CLASS/FILMMASKBOTTOM*
G04 Layer:  REF DES/ASSEMBLY_BOTTOM*
G04 Layer:  PACKAGE GEOMETRY/SILKSCREEN_BOTTOM*
G04 Layer:  DRAWING FORMAT/LAYER_PCB_STORY*
G04 Layer:  DRAWING FORMAT/LAYER_SILK_B*
G04 Layer:  BOARD GEOMETRY/SILKSCREEN_BOTTOM*
G04 *
G04 Offset:    (0.00 0.00)*
G04 Mirror:    No*
G04 Mode:      Positive*
G04 Rotation:  0*
G04 FullContactRelief:  No*
G04 UndefLineWidth:     6.00*
G04 ================== end FILE IDENTIFICATION RECORD ====================*
%FSLAX35Y35*MOIN*%
%IR0*IPPOS*OFA0.00000B0.00000*MIA0B0*SFA1.00000B1.00000*%
%ADD10C,.026*%
%ADD11C,.02*%
%ADD12C,.012*%
%ADD13C,.006*%
G75*
%LPD*%
G75*
G54D10*
X50299Y1946650D03*
X53999D03*
X42532Y1946783D03*
X44399Y1942250D03*
X38703Y1946754D03*
X34799Y1946750D03*
X46565Y1946703D03*
X44368Y1951450D03*
X210638Y62959D03*
X210634Y66863D03*
X215138Y72559D03*
X210685Y74725D03*
X210605Y70692D03*
X205938Y72528D03*
X210738Y78459D03*
Y82159D03*
X923761Y85550D03*
X932961Y85581D03*
X928461Y75981D03*
X928561Y91481D03*
X928508Y87747D03*
X928428Y83714D03*
X928561Y95181D03*
X928457Y79885D03*
G54D11*
G01X-71137Y-139897D02*
Y-219897D01*
G01D02*
X1129963D01*
G01X-75137Y-123897D02*
G02I-12000J0D01*
G01X-80287D02*
G02I-6850J0D01*
G01X-87137Y-139897D02*
Y-107897D01*
G01X-71137Y-123897D02*
X-103137D01*
G01X-71137Y-139897D02*
X1129963D01*
G01X-71137Y-175397D02*
X1129963D01*
G01X342463Y-139897D02*
Y-219897D01*
G01X479963Y-139897D02*
Y-219897D01*
G01X594963Y-139897D02*
Y-219897D01*
G01X762463Y-139897D02*
Y-219897D01*
G01X932463Y-139897D02*
Y-219897D01*
G01X1129963Y-139897D02*
Y-219897D01*
G01X1157963Y-123897D02*
G02I-12000J0D01*
G01X1152813D02*
G02I-6850J0D01*
G01X1145963Y-139897D02*
Y-107897D01*
G01X1161963Y-123897D02*
X1129963D01*
G54D12*
G01X0Y41772D02*
Y17214D01*
G01X-1Y129516D02*
Y104958D01*
G01Y324003D02*
Y300383D01*
G01X0Y933234D02*
Y905988D01*
G01X-1Y1092625D02*
Y1069005D01*
G01X0Y1309889D02*
Y1280567D01*
G01Y1986547D02*
Y1962927D01*
G01Y1912843D02*
Y1889223D01*
G01X1033464Y48297D02*
Y24677D01*
G01X1033465Y240964D02*
Y217344D01*
G01Y468660D02*
Y445040D01*
G01Y721094D02*
Y697474D01*
G01Y721094D02*
Y697474D01*
G01Y1020472D02*
Y996852D01*
G01Y1367680D02*
Y1344060D01*
G01Y1763340D02*
Y1739720D01*
G01X1033464Y1982862D02*
Y1959242D01*
G54D13*
G01X-89222Y-207897D02*
Y-190397D01*
G01X-80052D02*
Y-207897D01*
G01Y-199147D02*
X-89222D01*
G01X-67137Y-207897D02*
X-68447Y-207605D01*
X-69757Y-206439D01*
X-70631Y-204397D01*
X-71067Y-202064D01*
X-70631Y-199730D01*
X-69757Y-197689D01*
X-68447Y-196522D01*
X-67137Y-196231D01*
X-65827Y-196522D01*
X-64517Y-197689D01*
X-63644Y-199730D01*
X-63425Y-202064D01*
X-63644Y-204397D01*
X-64517Y-206439D01*
X-65827Y-207605D01*
X-67137Y-207897D01*
G01X-53349D02*
Y-196231D01*
G01Y-199147D02*
X-52475Y-197689D01*
X-51165Y-196522D01*
X-49419Y-196231D01*
X-47891Y-196522D01*
X-46580Y-197689D01*
X-45925Y-199730D01*
Y-207897D01*
G01X-35412Y-200022D02*
X-28425D01*
X-29080Y-197980D01*
X-30172Y-196814D01*
X-31700Y-196231D01*
X-33229Y-196522D01*
X-34539Y-197397D01*
X-35412Y-199439D01*
X-35849Y-201189D01*
Y-202939D01*
X-35412Y-204689D01*
X-34320Y-206439D01*
X-33010Y-207605D01*
X-31482Y-207897D01*
X-29954Y-207314D01*
X-28425Y-205564D01*
G01X-19222Y-213147D02*
X-17912Y-213730D01*
X-16165Y-213147D01*
X-15074Y-211981D01*
X-14200Y-210522D01*
X-12891Y-205856D01*
X-10052Y-196231D01*
G01X-17039D02*
X-12891Y-205856D01*
G01X22109Y-198564D02*
X22983Y-197689D01*
X23638Y-196231D01*
X24075Y-194188D01*
X23638Y-192439D01*
X22765Y-191272D01*
X21236Y-190397D01*
X15341D01*
Y-207897D01*
X22546D01*
X24075Y-206731D01*
X24948Y-204980D01*
X25385Y-202939D01*
X24948Y-200897D01*
X23638Y-199147D01*
X22109Y-198564D01*
X15341D01*
G01X41793Y-207897D02*
Y-196231D01*
G01Y-198272D02*
X40920Y-197106D01*
X39609Y-196522D01*
X38081Y-196231D01*
X36553Y-196814D01*
X35243Y-197980D01*
X34369Y-199730D01*
X33933Y-202064D01*
X34369Y-204397D01*
X35243Y-206147D01*
X36553Y-207314D01*
X38081Y-207897D01*
X39609Y-207605D01*
X40920Y-206731D01*
X41793Y-205564D01*
G01X59293Y-190397D02*
Y-207897D01*
G01Y-205273D02*
X58420Y-206731D01*
X57109Y-207605D01*
X55581Y-207897D01*
X53835Y-207314D01*
X52525Y-205856D01*
X51651Y-204106D01*
X51433Y-202064D01*
X51651Y-200022D01*
X52525Y-198272D01*
X53835Y-196814D01*
X55581Y-196231D01*
X57109Y-196522D01*
X58201Y-197106D01*
X59293Y-198272D01*
G01X69806Y-212272D02*
X71335Y-213439D01*
X73081Y-213730D01*
X74609Y-213439D01*
X75920Y-211981D01*
X76793Y-209939D01*
Y-196231D01*
G01Y-198564D02*
X75920Y-197397D01*
X74609Y-196522D01*
X73081Y-196231D01*
X71335Y-196814D01*
X70243Y-197980D01*
X69369Y-200022D01*
X68933Y-202064D01*
X69151Y-203814D01*
X70025Y-205856D01*
X71335Y-207314D01*
X73081Y-207897D01*
X74391Y-207605D01*
X75920Y-206439D01*
X76793Y-205273D01*
G01X87088Y-200022D02*
X94075D01*
X93420Y-197980D01*
X92328Y-196814D01*
X90800Y-196231D01*
X89271Y-196522D01*
X87961Y-197397D01*
X87088Y-199439D01*
X86651Y-201189D01*
Y-202939D01*
X87088Y-204689D01*
X88180Y-206439D01*
X89490Y-207605D01*
X91018Y-207897D01*
X92546Y-207314D01*
X94075Y-205564D01*
G01X104806Y-207897D02*
Y-196231D01*
G01Y-198564D02*
X105898Y-197397D01*
X106990Y-196522D01*
X108518Y-196231D01*
X109609Y-196522D01*
X110920Y-197397D01*
G01X138060Y-207897D02*
Y-190397D01*
X142426D01*
X144173Y-191272D01*
X145483Y-192439D01*
X146575Y-194188D01*
X147448Y-196231D01*
X147666Y-199147D01*
X147448Y-202064D01*
X146575Y-204106D01*
X145483Y-205856D01*
X144173Y-207022D01*
X142426Y-207897D01*
X138060D01*
G01X155996D02*
Y-190397D01*
X161236D01*
X162983Y-191272D01*
X164293Y-193314D01*
X164730Y-195647D01*
X164293Y-197980D01*
X163201Y-199730D01*
X161236Y-200606D01*
X155996D01*
G01X179609Y-198564D02*
X180483Y-197689D01*
X181138Y-196231D01*
X181575Y-194188D01*
X181138Y-192439D01*
X180265Y-191272D01*
X178736Y-190397D01*
X172841D01*
Y-207897D01*
X180046D01*
X181575Y-206731D01*
X182448Y-204980D01*
X182885Y-202939D01*
X182448Y-200897D01*
X181138Y-199147D01*
X179609Y-198564D01*
X172841D01*
G01X208496Y-190397D02*
Y-207897D01*
X217230D01*
G01X230363D02*
X229053Y-207605D01*
X227743Y-206439D01*
X226869Y-204397D01*
X226433Y-202064D01*
X226869Y-199730D01*
X227743Y-197689D01*
X229053Y-196522D01*
X230363Y-196231D01*
X231673Y-196522D01*
X232983Y-197689D01*
X233856Y-199730D01*
X234075Y-202064D01*
X233856Y-204397D01*
X232983Y-206439D01*
X231673Y-207605D01*
X230363Y-207897D01*
G01X242404Y-196231D02*
X245025Y-207897D01*
X247863Y-196231D01*
X250701Y-207897D01*
X253322Y-196231D01*
G01X278496Y-190397D02*
Y-207897D01*
X287230D01*
G01X300363D02*
X299053Y-207605D01*
X297743Y-206439D01*
X296869Y-204397D01*
X296433Y-202064D01*
X296869Y-199730D01*
X297743Y-197689D01*
X299053Y-196522D01*
X300363Y-196231D01*
X301673Y-196522D01*
X302983Y-197689D01*
X303856Y-199730D01*
X304075Y-202064D01*
X303856Y-204397D01*
X302983Y-206439D01*
X301673Y-207605D01*
X300363Y-207897D01*
G01X314588Y-205856D02*
X315680Y-207022D01*
X317208Y-207897D01*
X318518D01*
X319828Y-207314D01*
X320701Y-206439D01*
X321138Y-205273D01*
X320920Y-203522D01*
X320046Y-202647D01*
X316116Y-200897D01*
X315243Y-198855D01*
X315680Y-197397D01*
X316553Y-196522D01*
X317863Y-196231D01*
X319173Y-196522D01*
X320483Y-197397D01*
G01X332088Y-205856D02*
X333180Y-207022D01*
X334708Y-207897D01*
X336018D01*
X337328Y-207314D01*
X338201Y-206439D01*
X338638Y-205273D01*
X338420Y-203522D01*
X337546Y-202647D01*
X333616Y-200897D01*
X332743Y-198855D01*
X333180Y-197397D01*
X334053Y-196522D01*
X335363Y-196231D01*
X336673Y-196522D01*
X337983Y-197397D01*
G01X94686Y-164897D02*
Y-147397D01*
X100363Y-161980D01*
X106040Y-147397D01*
Y-164897D01*
G01X117863D02*
X116553Y-164605D01*
X115243Y-163439D01*
X114369Y-161397D01*
X113933Y-159064D01*
X114369Y-156730D01*
X115243Y-154689D01*
X116553Y-153522D01*
X117863Y-153231D01*
X119173Y-153522D01*
X120483Y-154689D01*
X121356Y-156730D01*
X121575Y-159064D01*
X121356Y-161397D01*
X120483Y-163439D01*
X119173Y-164605D01*
X117863Y-164897D01*
G01X139293Y-147397D02*
Y-164897D01*
G01Y-162273D02*
X138420Y-163731D01*
X137109Y-164605D01*
X135581Y-164897D01*
X133835Y-164314D01*
X132525Y-162856D01*
X131651Y-161106D01*
X131433Y-159064D01*
X131651Y-157022D01*
X132525Y-155272D01*
X133835Y-153814D01*
X135581Y-153231D01*
X137109Y-153522D01*
X138201Y-154106D01*
X139293Y-155272D01*
G01X149588Y-157022D02*
X156575D01*
X155920Y-154980D01*
X154828Y-153814D01*
X153300Y-153231D01*
X151771Y-153522D01*
X150461Y-154397D01*
X149588Y-156439D01*
X149151Y-158189D01*
Y-159939D01*
X149588Y-161689D01*
X150680Y-163439D01*
X151990Y-164605D01*
X153518Y-164897D01*
X155046Y-164314D01*
X156575Y-162564D01*
G01X170363Y-164897D02*
Y-147397D01*
G01X376163Y-209897D02*
Y-192397D01*
X373543Y-195897D01*
G01Y-209897D02*
X378783D01*
G01X396283D02*
Y-192397D01*
X388204Y-204939D01*
X399122D01*
G01X406360Y-207273D02*
X407669Y-208731D01*
X409198Y-209605D01*
X411163Y-209897D01*
X413128Y-209314D01*
X414656Y-208147D01*
X415748Y-206106D01*
X415966Y-203772D01*
X415530Y-201439D01*
X414438Y-199980D01*
X412909Y-198814D01*
X411381Y-198522D01*
X409853Y-198814D01*
X407888Y-199980D01*
X408543Y-192397D01*
X414438D01*
G01X431283Y-209897D02*
Y-192397D01*
X423204Y-204939D01*
X434122D01*
G01X441360Y-207273D02*
X442669Y-208731D01*
X444198Y-209605D01*
X446163Y-209897D01*
X448128Y-209314D01*
X449656Y-208147D01*
X450748Y-206106D01*
X450966Y-203772D01*
X450530Y-201439D01*
X449438Y-199980D01*
X447909Y-198814D01*
X446381Y-198522D01*
X444853Y-198814D01*
X442888Y-199980D01*
X443543Y-192397D01*
X449438D01*
G01X363046Y-164897D02*
Y-147397D01*
X368286D01*
X370033Y-148272D01*
X371343Y-150314D01*
X371780Y-152647D01*
X371343Y-154980D01*
X370251Y-156730D01*
X368286Y-157606D01*
X363046D01*
G01X389716Y-148856D02*
X388406Y-147980D01*
X386878Y-147397D01*
X385131D01*
X383166Y-148272D01*
X381638Y-149730D01*
X380546Y-151481D01*
X379673Y-154397D01*
X379454Y-157022D01*
X379891Y-159647D01*
X380546Y-161397D01*
X381856Y-163147D01*
X383385Y-164314D01*
X384913Y-164897D01*
X386441D01*
X387970Y-164314D01*
X389280Y-163439D01*
X390372Y-162273D01*
G01X404159Y-155564D02*
X405033Y-154689D01*
X405688Y-153231D01*
X406125Y-151188D01*
X405688Y-149439D01*
X404815Y-148272D01*
X403286Y-147397D01*
X397391D01*
Y-164897D01*
X404596D01*
X406125Y-163731D01*
X406998Y-161980D01*
X407435Y-159939D01*
X406998Y-157897D01*
X405688Y-156147D01*
X404159Y-155564D01*
X397391D01*
G01X413363Y-170730D02*
X426463D01*
G01X432391Y-164897D02*
Y-147397D01*
X442435Y-164897D01*
Y-147397D01*
G01X454913Y-164897D02*
X453166Y-164605D01*
X451638Y-163439D01*
X450328Y-161689D01*
X449454Y-159647D01*
X449018Y-157314D01*
Y-154980D01*
X449454Y-152647D01*
X450328Y-150605D01*
X451638Y-148856D01*
X453166Y-147689D01*
X454913Y-147397D01*
X456659Y-147689D01*
X458188Y-148856D01*
X459498Y-150605D01*
X460372Y-152647D01*
X460808Y-154980D01*
Y-157314D01*
X460372Y-159647D01*
X459498Y-161689D01*
X458188Y-163439D01*
X456659Y-164605D01*
X454913Y-164897D01*
G01X505754Y-147397D02*
X511213Y-164897D01*
X516672Y-147397D01*
G01X533080Y-164897D02*
X524346D01*
Y-147397D01*
X533080D01*
G01X529586Y-155855D02*
X524346D01*
G01X541846Y-164897D02*
Y-147397D01*
X547305D01*
X549051Y-148272D01*
X550143Y-149439D01*
X550580Y-151772D01*
X550143Y-154106D01*
X548833Y-155564D01*
X547305Y-156439D01*
X541846D01*
G01X547305D02*
X550580Y-164897D01*
G01X563713Y-165480D02*
X563276Y-165189D01*
Y-164605D01*
X563713Y-164314D01*
X564150Y-164605D01*
Y-165189D01*
X563713Y-165480D01*
G01X524128Y-207564D02*
X525875Y-209022D01*
X527840Y-209897D01*
X529586D01*
X531333Y-209022D01*
X532643Y-207564D01*
X533298Y-205522D01*
X532861Y-203481D01*
X531770Y-201730D01*
X529805Y-200564D01*
X527185Y-199980D01*
X525656Y-198814D01*
X525001Y-196772D01*
X525438Y-194730D01*
X526530Y-193272D01*
X528058Y-192397D01*
X529586D01*
X531115Y-192980D01*
X532425Y-194439D01*
G01X540754Y-209897D02*
X546213Y-192397D01*
X551672Y-209897D01*
G01X549706Y-203772D02*
X542719D01*
G01X711917Y-200564D02*
X711043Y-199689D01*
X710388Y-198231D01*
X709951Y-196188D01*
X710388Y-194439D01*
X711261Y-193272D01*
X712790Y-192397D01*
X718685D01*
Y-209897D01*
X711480D01*
X709951Y-208731D01*
X709078Y-206980D01*
X708641Y-204939D01*
X709078Y-202897D01*
X710388Y-201147D01*
X711917Y-200564D01*
X718685D01*
G01X700748Y-207564D02*
X699001Y-209022D01*
X697036Y-209897D01*
X695290D01*
X693543Y-209022D01*
X692233Y-207564D01*
X691578Y-205522D01*
X692015Y-203481D01*
X693106Y-201730D01*
X695071Y-200564D01*
X697691Y-199980D01*
X699220Y-198814D01*
X699875Y-196772D01*
X699438Y-194730D01*
X698346Y-193272D01*
X696818Y-192397D01*
X695290D01*
X693761Y-192980D01*
X692451Y-194439D01*
G01X681283Y-192397D02*
X676043D01*
G01X678663D02*
Y-209897D01*
G01X681283D02*
X676043D01*
G01X665530Y-192397D02*
Y-209897D01*
X656796D01*
G01X648466D02*
Y-192397D01*
G01X640170D02*
X648466Y-203189D01*
G01X638860Y-209897D02*
X644755Y-198231D01*
G01X630546Y-147397D02*
Y-164897D01*
X639280D01*
G01X656343D02*
Y-153231D01*
G01Y-155272D02*
X655470Y-154106D01*
X654159Y-153522D01*
X652631Y-153231D01*
X651103Y-153814D01*
X649793Y-154980D01*
X648919Y-156730D01*
X648483Y-159064D01*
X648919Y-161397D01*
X649793Y-163147D01*
X651103Y-164314D01*
X652631Y-164897D01*
X654159Y-164605D01*
X655470Y-163731D01*
X656343Y-162564D01*
G01X665328Y-170147D02*
X666638Y-170730D01*
X668385Y-170147D01*
X669476Y-168981D01*
X670350Y-167522D01*
X671659Y-162856D01*
X674498Y-153231D01*
G01X667511D02*
X671659Y-162856D01*
G01X684138Y-157022D02*
X691125D01*
X690470Y-154980D01*
X689378Y-153814D01*
X687850Y-153231D01*
X686321Y-153522D01*
X685011Y-154397D01*
X684138Y-156439D01*
X683701Y-158189D01*
Y-159939D01*
X684138Y-161689D01*
X685230Y-163439D01*
X686540Y-164605D01*
X688068Y-164897D01*
X689596Y-164314D01*
X691125Y-162564D01*
G01X701856Y-164897D02*
Y-153231D01*
G01Y-155564D02*
X702948Y-154397D01*
X704040Y-153522D01*
X705568Y-153231D01*
X706659Y-153522D01*
X707970Y-154397D01*
G01X719138Y-162856D02*
X720230Y-164022D01*
X721758Y-164897D01*
X723068D01*
X724378Y-164314D01*
X725251Y-163439D01*
X725688Y-162273D01*
X725470Y-160522D01*
X724596Y-159647D01*
X720666Y-157897D01*
X719793Y-155855D01*
X720230Y-154397D01*
X721103Y-153522D01*
X722413Y-153231D01*
X723723Y-153522D01*
X725033Y-154397D01*
G01X790596Y-209897D02*
Y-192397D01*
X796055D01*
X797801Y-193272D01*
X798893Y-194439D01*
X799330Y-196772D01*
X798893Y-199106D01*
X797583Y-200564D01*
X796055Y-201439D01*
X790596D01*
G01X796055D02*
X799330Y-209897D01*
G01X809188Y-202022D02*
X816175D01*
X815520Y-199980D01*
X814428Y-198814D01*
X812900Y-198231D01*
X811371Y-198522D01*
X810061Y-199397D01*
X809188Y-201439D01*
X808751Y-203189D01*
Y-204939D01*
X809188Y-206689D01*
X810280Y-208439D01*
X811590Y-209605D01*
X813118Y-209897D01*
X814646Y-209314D01*
X816175Y-207564D01*
G01X826033Y-209897D02*
Y-192397D01*
G01Y-201147D02*
X827125Y-199397D01*
X828435Y-198522D01*
X829745Y-198231D01*
X831709Y-198814D01*
X833020Y-199980D01*
X833893Y-202022D01*
Y-204355D01*
X833456Y-206689D01*
X832583Y-208439D01*
X831055Y-209605D01*
X829745Y-209897D01*
X828435Y-209605D01*
X827125Y-208731D01*
X826033Y-207273D01*
G01X844188Y-202022D02*
X851175D01*
X850520Y-199980D01*
X849428Y-198814D01*
X847900Y-198231D01*
X846371Y-198522D01*
X845061Y-199397D01*
X844188Y-201439D01*
X843751Y-203189D01*
Y-204939D01*
X844188Y-206689D01*
X845280Y-208439D01*
X846590Y-209605D01*
X848118Y-209897D01*
X849646Y-209314D01*
X851175Y-207564D01*
G01X868456Y-199689D02*
X866928Y-198522D01*
X865618Y-198231D01*
X863871Y-198814D01*
X862561Y-199980D01*
X861688Y-202022D01*
X861469Y-204064D01*
X861688Y-206106D01*
X862561Y-207856D01*
X863871Y-209314D01*
X865618Y-209897D01*
X867146Y-209314D01*
X868456Y-208147D01*
G01X885956Y-199689D02*
X884428Y-198522D01*
X883118Y-198231D01*
X881371Y-198814D01*
X880061Y-199980D01*
X879188Y-202022D01*
X878969Y-204064D01*
X879188Y-206106D01*
X880061Y-207856D01*
X881371Y-209314D01*
X883118Y-209897D01*
X884646Y-209314D01*
X885956Y-208147D01*
G01X903893Y-209897D02*
Y-198231D01*
G01Y-200272D02*
X903020Y-199106D01*
X901709Y-198522D01*
X900181Y-198231D01*
X898653Y-198814D01*
X897343Y-199980D01*
X896469Y-201730D01*
X896033Y-204064D01*
X896469Y-206397D01*
X897343Y-208147D01*
X898653Y-209314D01*
X900181Y-209897D01*
X901709Y-209605D01*
X903020Y-208731D01*
X903893Y-207564D01*
G01X781410Y-164897D02*
Y-147397D01*
X785776D01*
X787523Y-148272D01*
X788833Y-149439D01*
X789925Y-151188D01*
X790798Y-153231D01*
X791016Y-156147D01*
X790798Y-159064D01*
X789925Y-161106D01*
X788833Y-162856D01*
X787523Y-164022D01*
X785776Y-164897D01*
X781410D01*
G01X800438Y-157022D02*
X807425D01*
X806770Y-154980D01*
X805678Y-153814D01*
X804150Y-153231D01*
X802621Y-153522D01*
X801311Y-154397D01*
X800438Y-156439D01*
X800001Y-158189D01*
Y-159939D01*
X800438Y-161689D01*
X801530Y-163439D01*
X802840Y-164605D01*
X804368Y-164897D01*
X805896Y-164314D01*
X807425Y-162564D01*
G01X817938Y-162856D02*
X819030Y-164022D01*
X820558Y-164897D01*
X821868D01*
X823178Y-164314D01*
X824051Y-163439D01*
X824488Y-162273D01*
X824270Y-160522D01*
X823396Y-159647D01*
X819466Y-157897D01*
X818593Y-155855D01*
X819030Y-154397D01*
X819903Y-153522D01*
X821213Y-153231D01*
X822523Y-153522D01*
X823833Y-154397D01*
G01X838713Y-153231D02*
Y-164897D01*
G01Y-148564D02*
X838276Y-148272D01*
Y-147689D01*
X838713Y-147397D01*
X839150Y-147689D01*
Y-148272D01*
X838713Y-148564D01*
G01X853156Y-169272D02*
X854685Y-170439D01*
X856431Y-170730D01*
X857959Y-170439D01*
X859270Y-168981D01*
X860143Y-166939D01*
Y-153231D01*
G01Y-155564D02*
X859270Y-154397D01*
X857959Y-153522D01*
X856431Y-153231D01*
X854685Y-153814D01*
X853593Y-154980D01*
X852719Y-157022D01*
X852283Y-159064D01*
X852501Y-160814D01*
X853375Y-162856D01*
X854685Y-164314D01*
X856431Y-164897D01*
X857741Y-164605D01*
X859270Y-163439D01*
X860143Y-162273D01*
G01X870001Y-164897D02*
Y-153231D01*
G01Y-156147D02*
X870875Y-154689D01*
X872185Y-153522D01*
X873931Y-153231D01*
X875459Y-153522D01*
X876770Y-154689D01*
X877425Y-156730D01*
Y-164897D01*
G01X887938Y-157022D02*
X894925D01*
X894270Y-154980D01*
X893178Y-153814D01*
X891650Y-153231D01*
X890121Y-153522D01*
X888811Y-154397D01*
X887938Y-156439D01*
X887501Y-158189D01*
Y-159939D01*
X887938Y-161689D01*
X889030Y-163439D01*
X890340Y-164605D01*
X891868Y-164897D01*
X893396Y-164314D01*
X894925Y-162564D01*
G01X905656Y-164897D02*
Y-153231D01*
G01Y-155564D02*
X906748Y-154397D01*
X907840Y-153522D01*
X909368Y-153231D01*
X910459Y-153522D01*
X911770Y-154397D01*
G01X952413Y-192397D02*
X950666Y-192980D01*
X949356Y-194439D01*
X948483Y-196188D01*
X947828Y-198522D01*
X947610Y-201147D01*
X947828Y-203772D01*
X948483Y-206106D01*
X949356Y-207856D01*
X950666Y-209314D01*
X952413Y-209897D01*
X954159Y-209314D01*
X955470Y-207856D01*
X956343Y-206106D01*
X956998Y-203772D01*
X957216Y-201147D01*
X956998Y-198522D01*
X956343Y-196188D01*
X955470Y-194439D01*
X954159Y-192980D01*
X952413Y-192397D01*
G01X969913Y-209897D02*
X971441Y-209605D01*
X973188Y-208731D01*
X974280Y-207273D01*
X974716Y-205230D01*
X974280Y-203189D01*
X972970Y-201439D01*
X971005Y-200564D01*
X968821D01*
X967511Y-199980D01*
X966419Y-198522D01*
X965983Y-196481D01*
X966638Y-194439D01*
X968166Y-192980D01*
X969913Y-192397D01*
X971659Y-192980D01*
X973188Y-194439D01*
X973843Y-196481D01*
X973406Y-198522D01*
X972315Y-199980D01*
X971005Y-200564D01*
X968821D01*
X966856Y-201439D01*
X965546Y-203189D01*
X965110Y-205230D01*
X965546Y-207273D01*
X966638Y-208731D01*
X968385Y-209605D01*
X969913Y-209897D01*
G01X983483Y-210480D02*
X991343Y-192397D01*
G01X1004913D02*
X1003166Y-192980D01*
X1001856Y-194439D01*
X1000983Y-196188D01*
X1000328Y-198522D01*
X1000110Y-201147D01*
X1000328Y-203772D01*
X1000983Y-206106D01*
X1001856Y-207856D01*
X1003166Y-209314D01*
X1004913Y-209897D01*
X1006659Y-209314D01*
X1007970Y-207856D01*
X1008843Y-206106D01*
X1009498Y-203772D01*
X1009716Y-201147D01*
X1009498Y-198522D01*
X1008843Y-196188D01*
X1007970Y-194439D01*
X1006659Y-192980D01*
X1004913Y-192397D01*
G01X1022413Y-209897D02*
Y-192397D01*
X1019793Y-195897D01*
G01Y-209897D02*
X1025033D01*
G01X1035983Y-210480D02*
X1043843Y-192397D01*
G01X1053265Y-195314D02*
X1054575Y-193564D01*
X1056103Y-192689D01*
X1057850Y-192397D01*
X1060033Y-192980D01*
X1061561Y-194439D01*
X1061998Y-196188D01*
X1061780Y-197939D01*
X1060906Y-199397D01*
X1056540Y-202314D01*
X1054575Y-204355D01*
X1053265Y-207273D01*
X1052828Y-209897D01*
X1061998D01*
G01X1074913Y-192397D02*
X1073166Y-192980D01*
X1071856Y-194439D01*
X1070983Y-196188D01*
X1070328Y-198522D01*
X1070110Y-201147D01*
X1070328Y-203772D01*
X1070983Y-206106D01*
X1071856Y-207856D01*
X1073166Y-209314D01*
X1074913Y-209897D01*
X1076659Y-209314D01*
X1077970Y-207856D01*
X1078843Y-206106D01*
X1079498Y-203772D01*
X1079716Y-201147D01*
X1079498Y-198522D01*
X1078843Y-196188D01*
X1077970Y-194439D01*
X1076659Y-192980D01*
X1074913Y-192397D01*
G01X1092413Y-209897D02*
Y-192397D01*
X1089793Y-195897D01*
G01Y-209897D02*
X1095033D01*
G01X1112533D02*
Y-192397D01*
X1104454Y-204939D01*
X1115372D01*
G01X1000110Y-164897D02*
Y-147397D01*
X1004476D01*
X1006223Y-148272D01*
X1007533Y-149439D01*
X1008625Y-151188D01*
X1009498Y-153231D01*
X1009716Y-156147D01*
X1009498Y-159064D01*
X1008625Y-161106D01*
X1007533Y-162856D01*
X1006223Y-164022D01*
X1004476Y-164897D01*
X1000110D01*
G01X1026343D02*
Y-153231D01*
G01Y-155272D02*
X1025470Y-154106D01*
X1024159Y-153522D01*
X1022631Y-153231D01*
X1021103Y-153814D01*
X1019793Y-154980D01*
X1018919Y-156730D01*
X1018483Y-159064D01*
X1018919Y-161397D01*
X1019793Y-163147D01*
X1021103Y-164314D01*
X1022631Y-164897D01*
X1024159Y-164605D01*
X1025470Y-163731D01*
X1026343Y-162564D01*
G01X1039913Y-147397D02*
Y-164897D01*
G01X1036856Y-153231D02*
X1042970D01*
G01X1054138Y-157022D02*
X1061125D01*
X1060470Y-154980D01*
X1059378Y-153814D01*
X1057850Y-153231D01*
X1056321Y-153522D01*
X1055011Y-154397D01*
X1054138Y-156439D01*
X1053701Y-158189D01*
Y-159939D01*
X1054138Y-161689D01*
X1055230Y-163439D01*
X1056540Y-164605D01*
X1058068Y-164897D01*
X1059596Y-164314D01*
X1061125Y-162564D01*
M02*
